(kicad_pcb
	(version 20260206)
	(generator "pcbnew")
	(generator_version "10.0")
	(general
		(thickness 1.6)
		(legacy_teardrops no)
	)
	(paper "A4")
	(title_block
		(title "01162023_DA0F0TEBIF0_F0T_Expander_BD_F_brd_V02_OCP.brd")
		(comment 1 "Grand Teton / footprints 6986-6991 of 9728")
	)
	(layers
		(0 "F.Cu" signal "TOP")
		(4 "In1.Cu" signal "GND")
		(6 "In2.Cu" signal "VCC")
		(8 "In3.Cu" signal "VCC1")
		(10 "In4.Cu" signal "GND1")
		(12 "In5.Cu" signal "IN1")
		(14 "In6.Cu" signal "GND2")
		(16 "In7.Cu" signal "IN2")
		(18 "In8.Cu" signal "GND3")
		(20 "In9.Cu" signal "IN3")
		(22 "In10.Cu" signal "GND4")
		(24 "In11.Cu" signal "IN4")
		(26 "In12.Cu" signal "GND5")
		(28 "In13.Cu" signal "IN5")
		(30 "In14.Cu" signal "GND6")
		(32 "In15.Cu" signal "IN6")
		(34 "In16.Cu" signal "GND7")
		(2 "B.Cu" signal "BOTTOM")
		(9 "F.Adhes" user "F.Adhesive")
		(11 "B.Adhes" user "B.Adhesive")
		(13 "F.Paste" user "Package Geometry/Pastemask Top")
		(15 "B.Paste" user "Package Geometry/Pastemask Bottom")
		(5 "F.SilkS" user "Ref Des/Silkscreen Top")
		(7 "B.SilkS" user "Ref Des/Silkscreen Bottom")
		(1 "F.Mask" user "Board Geometry/Soldermask Top")
		(3 "B.Mask" user "Board Geometry/Soldermask Bottom")
		(17 "Dwgs.User" user "User.Drawings")
		(19 "Cmts.User" user "User.Comments")
		(21 "Eco1.User" user "User.Eco1")
		(23 "Eco2.User" user "User.Eco2")
		(25 "Edge.Cuts" user "Board Geometry/Outline")
		(27 "Margin" user)
		(31 "F.CrtYd" user "Package Geometry/Place Bound Top")
		(29 "B.CrtYd" user "Package Geometry/Place Bound Bottom")
		(35 "F.Fab" user "Ref Des/Assembly Top")
		(33 "B.Fab" user "Ref Des/Assembly Bottom")
	)
	(footprint ""
		(layer "F.Cu")
		(at 460.31531 -258.331208 -90)
		(property "Reference" "R6563"
			(at 0 0 270)
			(layer "F.SilkS")
			(hide yes)
			(effects
				(font
					(size 1.27 1.27)
				)
			)
		)
		(property "Value" ""
			(at 0 0 270)
			(layer "F.Fab")
			(effects
				(font
					(size 1.27 1.27)
				)
			)
		)
		(duplicate_pad_numbers_are_jumpers no)
		(fp_line
			(start -0.7874 0.4064)
			(end -0.7874 -0.4064)
			(stroke
				(width 0.1524)
				(type default)
			)
			(layer "F.SilkS")
		)
		(fp_line
			(start 0.7874 0.4064)
			(end -0.7874 0.4064)
			(stroke
				(width 0.1524)
				(type default)
			)
			(layer "F.SilkS")
		)
		(fp_line
			(start -0.7874 -0.4064)
			(end 0.7874 -0.4064)
			(stroke
				(width 0.1524)
				(type default)
			)
			(layer "F.SilkS")
		)
		(fp_line
			(start 0.7874 -0.4064)
			(end 0.7874 0.4064)
			(stroke
				(width 0.1524)
				(type default)
			)
			(layer "F.SilkS")
		)
		(fp_line
			(start -0.67945 0.3048)
			(end -0.67945 -0.305054)
			(stroke
				(width 0.1)
				(type default)
			)
			(layer "F.Fab")
		)
		(fp_line
			(start -0.12065 0.3048)
			(end -0.67945 0.3048)
			(stroke
				(width 0.1)
				(type default)
			)
			(layer "F.Fab")
		)
		(fp_line
			(start 0.120396 0.3048)
			(end 0.120396 0.2794)
			(stroke
				(width 0.1)
				(type default)
			)
			(layer "F.Fab")
		)
		(fp_line
			(start 0.67945 0.3048)
			(end 0.120396 0.3048)
			(stroke
				(width 0.1)
				(type default)
			)
			(layer "F.Fab")
		)
		(fp_line
			(start -0.12065 0.2794)
			(end -0.12065 0.3048)
			(stroke
				(width 0.1)
				(type default)
			)
			(layer "F.Fab")
		)
		(fp_line
			(start 0.120396 0.2794)
			(end -0.12065 0.2794)
			(stroke
				(width 0.1)
				(type default)
			)
			(layer "F.Fab")
		)
		(fp_line
			(start -0.12065 -0.2794)
			(end 0.12065 -0.2794)
			(stroke
				(width 0.1)
				(type default)
			)
			(layer "F.Fab")
		)
		(fp_line
			(start 0.12065 -0.2794)
			(end 0.12065 -0.3048)
			(stroke
				(width 0.1)
				(type default)
			)
			(layer "F.Fab")
		)
		(fp_line
			(start 0.12065 -0.3048)
			(end 0.67945 -0.3048)
			(stroke
				(width 0.1)
				(type default)
			)
			(layer "F.Fab")
		)
		(fp_line
			(start 0.67945 -0.3048)
			(end 0.67945 0.3048)
			(stroke
				(width 0.1)
				(type default)
			)
			(layer "F.Fab")
		)
		(fp_line
			(start -0.67945 -0.305054)
			(end -0.12065 -0.305054)
			(stroke
				(width 0.1)
				(type default)
			)
			(layer "F.Fab")
		)
		(fp_line
			(start -0.12065 -0.305054)
			(end -0.12065 -0.2794)
			(stroke
				(width 0.1)
				(type default)
			)
			(layer "F.Fab")
		)
		(pad "1" smd circle
			(at -0.40005 0 270)
			(size 0 0)
			(layers "F.Cu" "F.Mask" "F.Paste")
			(net "P1V25_SERDES_VDDPLL_PEX3")
		)
		(pad "2" smd circle
			(at 0.40005 0 270)
			(size 0 0)
			(layers "F.Cu" "F.Mask" "F.Paste")
			(net "P1V25_SERDES_VDDPLL_PEX3_C10")
		)
	)
	(footprint ""
		(layer "F.Cu")
		(at 168.367964 -55.083456)
		(property "Reference" "PC396"
			(at 0 0 0)
			(layer "F.SilkS")
			(hide yes)
			(effects
				(font
					(size 1.27 1.27)
				)
			)
		)
		(property "Value" ""
			(at 0 0 0)
			(layer "F.Fab")
			(effects
				(font
					(size 1.27 1.27)
				)
			)
		)
		(duplicate_pad_numbers_are_jumpers no)
		(fp_line
			(start -0.7874 -0.4064)
			(end 0.7874 -0.4064)
			(stroke
				(width 0.1524)
				(type default)
			)
			(layer "F.SilkS")
		)
		(fp_line
			(start -0.7874 0.4064)
			(end -0.7874 -0.4064)
			(stroke
				(width 0.1524)
				(type default)
			)
			(layer "F.SilkS")
		)
		(fp_line
			(start 0.7874 -0.4064)
			(end 0.7874 0.4064)
			(stroke
				(width 0.1524)
				(type default)
			)
			(layer "F.SilkS")
		)
		(fp_line
			(start 0.7874 0.4064)
			(end -0.7874 0.4064)
			(stroke
				(width 0.1524)
				(type default)
			)
			(layer "F.SilkS")
		)
		(fp_line
			(start -0.67945 -0.305054)
			(end -0.12065 -0.305054)
			(stroke
				(width 0.1)
				(type default)
			)
			(layer "F.Fab")
		)
		(fp_line
			(start -0.67945 0.3048)
			(end -0.67945 -0.305054)
			(stroke
				(width 0.1)
				(type default)
			)
			(layer "F.Fab")
		)
		(fp_line
			(start -0.12065 -0.305054)
			(end -0.12065 -0.2794)
			(stroke
				(width 0.1)
				(type default)
			)
			(layer "F.Fab")
		)
		(fp_line
			(start -0.12065 -0.2794)
			(end 0.12065 -0.2794)
			(stroke
				(width 0.1)
				(type default)
			)
			(layer "F.Fab")
		)
		(fp_line
			(start -0.12065 0.2794)
			(end -0.12065 0.3048)
			(stroke
				(width 0.1)
				(type default)
			)
			(layer "F.Fab")
		)
		(fp_line
			(start -0.12065 0.3048)
			(end -0.67945 0.3048)
			(stroke
				(width 0.1)
				(type default)
			)
			(layer "F.Fab")
		)
		(fp_line
			(start 0.120396 0.2794)
			(end -0.12065 0.2794)
			(stroke
				(width 0.1)
				(type default)
			)
			(layer "F.Fab")
		)
		(fp_line
			(start 0.120396 0.3048)
			(end 0.120396 0.2794)
			(stroke
				(width 0.1)
				(type default)
			)
			(layer "F.Fab")
		)
		(fp_line
			(start 0.12065 -0.3048)
			(end 0.67945 -0.3048)
			(stroke
				(width 0.1)
				(type default)
			)
			(layer "F.Fab")
		)
		(fp_line
			(start 0.12065 -0.2794)
			(end 0.12065 -0.3048)
			(stroke
				(width 0.1)
				(type default)
			)
			(layer "F.Fab")
		)
		(fp_line
			(start 0.67945 -0.3048)
			(end 0.67945 0.3048)
			(stroke
				(width 0.1)
				(type default)
			)
			(layer "F.Fab")
		)
		(fp_line
			(start 0.67945 0.3048)
			(end 0.120396 0.3048)
			(stroke
				(width 0.1)
				(type default)
			)
			(layer "F.Fab")
		)
		(pad "1" smd circle
			(at -0.40005 0)
			(size 0 0)
			(layers "F.Cu" "F.Mask" "F.Paste")
			(net "P5V_AUX")
		)
		(pad "2" smd circle
			(at 0.40005 0)
			(size 0 0)
			(layers "F.Cu" "F.Mask" "F.Paste")
			(net "GND")
		)
	)
	(footprint ""
		(layer "F.Cu")
		(at 83.293966 -34.248852)
		(property "Reference" "R5656"
			(at 0 0 0)
			(layer "F.SilkS")
			(hide yes)
			(effects
				(font
					(size 1.27 1.27)
				)
			)
		)
		(property "Value" ""
			(at 0 0 0)
			(layer "F.Fab")
			(effects
				(font
					(size 1.27 1.27)
				)
			)
		)
		(duplicate_pad_numbers_are_jumpers no)
		(fp_line
			(start -0.7874 -0.4064)
			(end 0.7874 -0.4064)
			(stroke
				(width 0.1524)
				(type default)
			)
			(layer "F.SilkS")
		)
		(fp_line
			(start -0.7874 0.4064)
			(end -0.7874 -0.4064)
			(stroke
				(width 0.1524)
				(type default)
			)
			(layer "F.SilkS")
		)
		(fp_line
			(start 0.7874 -0.4064)
			(end 0.7874 0.4064)
			(stroke
				(width 0.1524)
				(type default)
			)
			(layer "F.SilkS")
		)
		(fp_line
			(start 0.7874 0.4064)
			(end -0.7874 0.4064)
			(stroke
				(width 0.1524)
				(type default)
			)
			(layer "F.SilkS")
		)
		(fp_line
			(start -0.67945 -0.305054)
			(end -0.12065 -0.305054)
			(stroke
				(width 0.1)
				(type default)
			)
			(layer "F.Fab")
		)
		(fp_line
			(start -0.67945 0.3048)
			(end -0.67945 -0.305054)
			(stroke
				(width 0.1)
				(type default)
			)
			(layer "F.Fab")
		)
		(fp_line
			(start -0.12065 -0.305054)
			(end -0.12065 -0.2794)
			(stroke
				(width 0.1)
				(type default)
			)
			(layer "F.Fab")
		)
		(fp_line
			(start -0.12065 -0.2794)
			(end 0.12065 -0.2794)
			(stroke
				(width 0.1)
				(type default)
			)
			(layer "F.Fab")
		)
		(fp_line
			(start -0.12065 0.2794)
			(end -0.12065 0.3048)
			(stroke
				(width 0.1)
				(type default)
			)
			(layer "F.Fab")
		)
		(fp_line
			(start -0.12065 0.3048)
			(end -0.67945 0.3048)
			(stroke
				(width 0.1)
				(type default)
			)
			(layer "F.Fab")
		)
		(fp_line
			(start 0.120396 0.2794)
			(end -0.12065 0.2794)
			(stroke
				(width 0.1)
				(type default)
			)
			(layer "F.Fab")
		)
		(fp_line
			(start 0.120396 0.3048)
			(end 0.120396 0.2794)
			(stroke
				(width 0.1)
				(type default)
			)
			(layer "F.Fab")
		)
		(fp_line
			(start 0.12065 -0.3048)
			(end 0.67945 -0.3048)
			(stroke
				(width 0.1)
				(type default)
			)
			(layer "F.Fab")
		)
		(fp_line
			(start 0.12065 -0.2794)
			(end 0.12065 -0.3048)
			(stroke
				(width 0.1)
				(type default)
			)
			(layer "F.Fab")
		)
		(fp_line
			(start 0.67945 -0.3048)
			(end 0.67945 0.3048)
			(stroke
				(width 0.1)
				(type default)
			)
			(layer "F.Fab")
		)
		(fp_line
			(start 0.67945 0.3048)
			(end 0.120396 0.3048)
			(stroke
				(width 0.1)
				(type default)
			)
			(layer "F.Fab")
		)
		(pad "1" smd circle
			(at -0.40005 0)
			(size 0 0)
			(layers "F.Cu" "F.Mask" "F.Paste")
			(net "RST_SMB_SSD3_ISO_N")
		)
		(pad "2" smd circle
			(at 0.40005 0)
			(size 0 0)
			(layers "F.Cu" "F.Mask" "F.Paste")
			(net "P3V3_SSD3")
		)
	)
	(footprint ""
		(layer "F.Cu")
		(at 20.771104 -146.205956 180)
		(property "Reference" "C411"
			(at 0 0 180)
			(layer "F.SilkS")
			(hide yes)
			(effects
				(font
					(size 1.27 1.27)
				)
			)
		)
		(property "Value" ""
			(at 0 0 180)
			(layer "F.Fab")
			(effects
				(font
					(size 1.27 1.27)
				)
			)
		)
		(duplicate_pad_numbers_are_jumpers no)
		(fp_line
			(start 0.7874 0.4064)
			(end -0.7874 0.4064)
			(stroke
				(width 0.1524)
				(type default)
			)
			(layer "F.SilkS")
		)
		(fp_line
			(start 0.7874 -0.4064)
			(end 0.7874 0.4064)
			(stroke
				(width 0.1524)
				(type default)
			)
			(layer "F.SilkS")
		)
		(fp_line
			(start -0.7874 0.4064)
			(end -0.7874 -0.4064)
			(stroke
				(width 0.1524)
				(type default)
			)
			(layer "F.SilkS")
		)
		(fp_line
			(start -0.7874 -0.4064)
			(end 0.7874 -0.4064)
			(stroke
				(width 0.1524)
				(type default)
			)
			(layer "F.SilkS")
		)
		(fp_line
			(start 0.67945 0.3048)
			(end 0.120396 0.3048)
			(stroke
				(width 0.1)
				(type default)
			)
			(layer "F.Fab")
		)
		(fp_line
			(start 0.67945 -0.3048)
			(end 0.67945 0.3048)
			(stroke
				(width 0.1)
				(type default)
			)
			(layer "F.Fab")
		)
		(fp_line
			(start 0.12065 -0.2794)
			(end 0.12065 -0.3048)
			(stroke
				(width 0.1)
				(type default)
			)
			(layer "F.Fab")
		)
		(fp_line
			(start 0.12065 -0.3048)
			(end 0.67945 -0.3048)
			(stroke
				(width 0.1)
				(type default)
			)
			(layer "F.Fab")
		)
		(fp_line
			(start 0.120396 0.3048)
			(end 0.120396 0.2794)
			(stroke
				(width 0.1)
				(type default)
			)
			(layer "F.Fab")
		)
		(fp_line
			(start 0.120396 0.2794)
			(end -0.12065 0.2794)
			(stroke
				(width 0.1)
				(type default)
			)
			(layer "F.Fab")
		)
		(fp_line
			(start -0.12065 0.3048)
			(end -0.67945 0.3048)
			(stroke
				(width 0.1)
				(type default)
			)
			(layer "F.Fab")
		)
		(fp_line
			(start -0.12065 0.2794)
			(end -0.12065 0.3048)
			(stroke
				(width 0.1)
				(type default)
			)
			(layer "F.Fab")
		)
		(fp_line
			(start -0.12065 -0.2794)
			(end 0.12065 -0.2794)
			(stroke
				(width 0.1)
				(type default)
			)
			(layer "F.Fab")
		)
		(fp_line
			(start -0.12065 -0.305054)
			(end -0.12065 -0.2794)
			(stroke
				(width 0.1)
				(type default)
			)
			(layer "F.Fab")
		)
		(fp_line
			(start -0.67945 0.3048)
			(end -0.67945 -0.305054)
			(stroke
				(width 0.1)
				(type default)
			)
			(layer "F.Fab")
		)
		(fp_line
			(start -0.67945 -0.305054)
			(end -0.12065 -0.305054)
			(stroke
				(width 0.1)
				(type default)
			)
			(layer "F.Fab")
		)
		(pad "1" smd circle
			(at -0.40005 0 180)
			(size 0 0)
			(layers "F.Cu" "F.Mask" "F.Paste")
			(net "P12V_NIC0_VIN_P")
		)
		(pad "2" smd circle
			(at 0.40005 0 180)
			(size 0 0)
			(layers "F.Cu" "F.Mask" "F.Paste")
			(net "P12V_NIC0_VIN_N")
		)
	)
	(footprint ""
		(layer "F.Cu")
		(at 118.572534 -119.511826 90)
		(property "Reference" "PU70"
			(at -1.657096 3.245866 0)
			(unlocked yes)
			(layer "F.SilkS")
			(effects
				(font
					(size 0.7874 0.5842)
					(thickness 0.1524)
				)
			)
		)
		(property "Value" ""
			(at 0 0 90)
			(layer "F.Fab")
			(effects
				(font
					(size 1.27 1.27)
				)
			)
		)
		(duplicate_pad_numbers_are_jumpers no)
		(fp_line
			(start 1.239774 -1.495298)
			(end 1.239774 1.495298)
			(stroke
				(width 0.1524)
				(type default)
			)
			(layer "F.SilkS")
		)
		(fp_line
			(start -1.239774 -1.495298)
			(end 1.239774 -1.495298)
			(stroke
				(width 0.1524)
				(type default)
			)
			(layer "F.SilkS")
		)
		(fp_line
			(start 1.239774 1.495298)
			(end -1.239774 1.495298)
			(stroke
				(width 0.1524)
				(type default)
			)
			(layer "F.SilkS")
		)
		(fp_line
			(start -1.239774 1.495298)
			(end -1.239774 -1.495298)
			(stroke
				(width 0.1524)
				(type default)
			)
			(layer "F.SilkS")
		)
		(fp_poly
			(pts
				(xy -1.858264 -1.248918) (xy -2.576576 -0.530606) (xy -1.499108 -0.17145)
			)
			(stroke
				(width 0)
				(type default)
			)
			(fill yes)
			(layer "F.SilkS")
		)
		(fp_line
			(start 0.8001 -1.050036)
			(end 0.8001 1.050036)
			(stroke
				(width 0.1)
				(type default)
			)
			(layer "F.Fab")
		)
		(fp_line
			(start -0.8001 -1.050036)
			(end 0.8001 -1.050036)
			(stroke
				(width 0.1)
				(type default)
			)
			(layer "F.Fab")
		)
		(fp_line
			(start 0.8001 1.050036)
			(end -0.8001 1.050036)
			(stroke
				(width 0.1)
				(type default)
			)
			(layer "F.Fab")
		)
		(fp_line
			(start -0.8001 1.050036)
			(end -0.8001 -1.050036)
			(stroke
				(width 0.1)
				(type default)
			)
			(layer "F.Fab")
		)
		(fp_poly
			(pts
				(xy -2.458974 -0.508) (xy -2.458974 0.508) (xy -1.442974 0)
			)
			(stroke
				(width 0)
				(type default)
			)
			(fill yes)
			(layer "F.Fab")
		)
		(pad "1_2" smd circle
			(at -0.374904 0 180)
			(size 0 0)
			(layers "F.Cu" "F.Mask" "F.Paste")
			(net "P3V3_AUX")
		)
		(pad "3" smd rect
			(at -0.499872 0.999998 90)
			(size 0.254 0.7112)
			(layers "F.Cu" "F.Mask" "F.Paste")
			(net "GND")
		)
		(pad "4" smd rect
			(at 0 0.999998 90)
			(size 0.254 0.7112)
			(layers "F.Cu" "F.Mask" "F.Paste")
			(net "P3V3_CO_ILIMIT")
		)
		(pad "5" smd rect
			(at 0.499872 0.999998 90)
			(size 0.254 0.7112)
			(layers "F.Cu" "F.Mask" "F.Paste")
			(net "P3V3_CO_MODE")
		)
		(pad "6_7" smd circle
			(at 0.374904 0)
			(size 0 0)
			(layers "F.Cu" "F.Mask" "F.Paste")
			(net "P3V3")
		)
		(pad "8" smd rect
			(at 0.499872 -0.999998 90)
			(size 0.254 0.7112)
			(layers "F.Cu" "F.Mask" "F.Paste")
			(net "P3V3_CO_GATE")
		)
		(pad "9" smd rect
			(at 0 -0.999998 90)
			(size 0.254 0.7112)
			(layers "F.Cu" "F.Mask" "F.Paste")
			(net "P3V3_CO_EN")
		)
		(pad "10" smd rect
			(at -0.499872 -0.999998 90)
			(size 0.254 0.7112)
			(layers "F.Cu" "F.Mask" "F.Paste")
			(net "P3V3_CO_DV_DT")
		)
	)
	(footprint ""
		(layer "F.Cu")
		(at 320.354452 -219.579698 180)
		(property "Reference" "D18"
			(at 3.743452 -0.023368 0)
			(unlocked yes)
			(layer "F.SilkS")
			(effects
				(font
					(size 0.7874 0.5842)
					(thickness 0.1524)
				)
				(justify left)
			)
		)
		(property "Value" ""
			(at 0 0 180)
			(layer "F.Fab")
			(effects
				(font
					(size 1.27 1.27)
				)
			)
		)
		(duplicate_pad_numbers_are_jumpers no)
		(fp_line
			(start 1.16078 0.4826)
			(end -0.64008 0.4826)
			(stroke
				(width 0.1524)
				(type default)
			)
			(layer "F.SilkS")
		)
		(fp_line
			(start 1.16078 -0.4826)
			(end 1.16078 0.4826)
			(stroke
				(width 0.1524)
				(type default)
			)
			(layer "F.SilkS")
		)
		(fp_line
			(start 1.03378 0.4826)
			(end -0.79248 0.4826)
			(stroke
				(width 0.1524)
				(type default)
			)
			(layer "F.SilkS")
		)
		(fp_line
			(start 1.03378 -0.4826)
			(end 1.03378 0.4826)
			(stroke
				(width 0.1524)
				(type default)
			)
			(layer "F.SilkS")
		)
		(fp_line
			(start 0.90678 0.4826)
			(end -0.90678 0.4826)
			(stroke
				(width 0.1524)
				(type default)
			)
			(layer "F.SilkS")
		)
		(fp_line
			(start 0.90678 -0.4826)
			(end 0.90678 0.4826)
			(stroke
				(width 0.1524)
				(type default)
			)
			(layer "F.SilkS")
		)
		(fp_line
			(start -0.64008 -0.4826)
			(end 1.16078 -0.4826)
			(stroke
				(width 0.1524)
				(type default)
			)
			(layer "F.SilkS")
		)
		(fp_line
			(start -0.79248 -0.4826)
			(end 1.03378 -0.4826)
			(stroke
				(width 0.1524)
				(type default)
			)
			(layer "F.SilkS")
		)
		(fp_line
			(start -0.89408 -0.4826)
			(end 0.90678 -0.4826)
			(stroke
				(width 0.1524)
				(type default)
			)
			(layer "F.SilkS")
		)
		(fp_line
			(start -0.90678 0.4826)
			(end -0.90678 -0.4699)
			(stroke
				(width 0.1524)
				(type default)
			)
			(layer "F.SilkS")
		)
		(fp_line
			(start 0.499872 0.249936)
			(end -0.499872 0.249936)
			(stroke
				(width 0.1)
				(type default)
			)
			(layer "F.Fab")
		)
		(fp_line
			(start 0.499872 -0.249936)
			(end 0.499872 0.249936)
			(stroke
				(width 0.1)
				(type default)
			)
			(layer "F.Fab")
		)
		(fp_line
			(start -0.499872 0.249936)
			(end -0.499872 -0.249936)
			(stroke
				(width 0.1)
				(type default)
			)
			(layer "F.Fab")
		)
		(fp_line
			(start -0.499872 -0.249936)
			(end 0.499872 -0.249936)
			(stroke
				(width 0.1)
				(type default)
			)
			(layer "F.Fab")
		)
		(pad "A" smd rect
			(at -0.47498 0 180)
			(size 0.6096 0.7112)
			(layers "F.Cu" "F.Mask" "F.Paste")
			(net "LED_POSTCODE_R_5")
		)
		(pad "C" smd rect
			(at 0.47498 0 180)
			(size 0.6096 0.7112)
			(layers "F.Cu" "F.Mask" "F.Paste")
			(net "FPGA_DEBUG_LED_R_N")
		)
	)
)
